(kicad_pcb
	(version 20260206)
	(generator "pcbnew")
	(generator_version "10.0")
	(general
		(thickness 1.6)
		(legacy_teardrops no)
	)
	(paper "A4")
	(title_block
		(title "04192023_DAF0TMB3IC0_F0TG_MB_C_brd_V02_OCP.brd")
		(comment 1 "Grand Teton / footprints 4013-4019 of 8354")
	)
	(layers
		(0 "F.Cu" signal "TOP")
		(4 "In1.Cu" signal "GND")
		(6 "In2.Cu" signal "IN1")
		(8 "In3.Cu" signal "GND1")
		(10 "In4.Cu" signal "IN2")
		(12 "In5.Cu" signal "GND2")
		(14 "In6.Cu" signal "IN3")
		(16 "In7.Cu" signal "GND3")
		(18 "In8.Cu" signal "VCC")
		(20 "In9.Cu" signal "VCC1")
		(22 "In10.Cu" signal "GND4")
		(24 "In11.Cu" signal "IN4")
		(26 "In12.Cu" signal "GND5")
		(28 "In13.Cu" signal "IN5")
		(30 "In14.Cu" signal "GND6")
		(32 "In15.Cu" signal "IN6")
		(34 "In16.Cu" signal "GND7")
		(2 "B.Cu" signal "BOTTOM")
		(9 "F.Adhes" user "F.Adhesive")
		(11 "B.Adhes" user "B.Adhesive")
		(13 "F.Paste" user "Package Geometry/Pastemask Top")
		(15 "B.Paste" user "Package Geometry/Pastemask Bottom")
		(5 "F.SilkS" user "Ref Des/Silkscreen Top")
		(7 "B.SilkS" user "Ref Des/Silkscreen Bottom")
		(1 "F.Mask" user "Board Geometry/Soldermask Top")
		(3 "B.Mask" user "Board Geometry/Soldermask Bottom")
		(17 "Dwgs.User" user "User.Drawings")
		(19 "Cmts.User" user "User.Comments")
		(21 "Eco1.User" user "User.Eco1")
		(23 "Eco2.User" user "User.Eco2")
		(25 "Edge.Cuts" user "Board Geometry/Outline")
		(27 "Margin" user)
		(31 "F.CrtYd" user "Package Geometry/Place Bound Top")
		(29 "B.CrtYd" user "Package Geometry/Place Bound Bottom")
		(35 "F.Fab" user "Ref Des/Assembly Top")
		(33 "B.Fab" user "Ref Des/Assembly Bottom")
	)
	(footprint ""
		(layer "F.Cu")
		(at 361.046014 -259.845048)
		(property "Reference" "C2657"
			(at 0 0 0)
			(layer "F.SilkS")
			(hide yes)
			(effects
				(font
					(size 1.27 1.27)
				)
			)
		)
		(property "Value" ""
			(at 0 0 0)
			(layer "F.Fab")
			(effects
				(font
					(size 1.27 1.27)
				)
			)
		)
		(duplicate_pad_numbers_are_jumpers no)
		(fp_line
			(start -0.7874 -0.4064)
			(end 0.7874 -0.4064)
			(stroke
				(width 0.1524)
				(type default)
			)
			(layer "F.SilkS")
		)
		(fp_line
			(start -0.7874 0.4064)
			(end -0.7874 -0.4064)
			(stroke
				(width 0.1524)
				(type default)
			)
			(layer "F.SilkS")
		)
		(fp_line
			(start 0.7874 -0.4064)
			(end 0.7874 0.4064)
			(stroke
				(width 0.1524)
				(type default)
			)
			(layer "F.SilkS")
		)
		(fp_line
			(start 0.7874 0.4064)
			(end -0.7874 0.4064)
			(stroke
				(width 0.1524)
				(type default)
			)
			(layer "F.SilkS")
		)
		(fp_line
			(start -0.67945 -0.305054)
			(end -0.12065 -0.305054)
			(stroke
				(width 0.1)
				(type default)
			)
			(layer "F.Fab")
		)
		(fp_line
			(start -0.67945 0.3048)
			(end -0.67945 -0.305054)
			(stroke
				(width 0.1)
				(type default)
			)
			(layer "F.Fab")
		)
		(fp_line
			(start -0.12065 -0.305054)
			(end -0.12065 -0.2794)
			(stroke
				(width 0.1)
				(type default)
			)
			(layer "F.Fab")
		)
		(fp_line
			(start -0.12065 -0.2794)
			(end 0.12065 -0.2794)
			(stroke
				(width 0.1)
				(type default)
			)
			(layer "F.Fab")
		)
		(fp_line
			(start -0.12065 0.2794)
			(end -0.12065 0.3048)
			(stroke
				(width 0.1)
				(type default)
			)
			(layer "F.Fab")
		)
		(fp_line
			(start -0.12065 0.3048)
			(end -0.67945 0.3048)
			(stroke
				(width 0.1)
				(type default)
			)
			(layer "F.Fab")
		)
		(fp_line
			(start 0.120396 0.2794)
			(end -0.12065 0.2794)
			(stroke
				(width 0.1)
				(type default)
			)
			(layer "F.Fab")
		)
		(fp_line
			(start 0.120396 0.3048)
			(end 0.120396 0.2794)
			(stroke
				(width 0.1)
				(type default)
			)
			(layer "F.Fab")
		)
		(fp_line
			(start 0.12065 -0.3048)
			(end 0.67945 -0.3048)
			(stroke
				(width 0.1)
				(type default)
			)
			(layer "F.Fab")
		)
		(fp_line
			(start 0.12065 -0.2794)
			(end 0.12065 -0.3048)
			(stroke
				(width 0.1)
				(type default)
			)
			(layer "F.Fab")
		)
		(fp_line
			(start 0.67945 -0.3048)
			(end 0.67945 0.3048)
			(stroke
				(width 0.1)
				(type default)
			)
			(layer "F.Fab")
		)
		(fp_line
			(start 0.67945 0.3048)
			(end 0.120396 0.3048)
			(stroke
				(width 0.1)
				(type default)
			)
			(layer "F.Fab")
		)
		(pad "1" smd circle
			(at -0.40005 0)
			(size 0 0)
			(layers "F.Cu" "F.Mask" "F.Paste")
			(net "PVDD11_S3_P0")
		)
		(pad "2" smd circle
			(at 0.40005 0)
			(size 0 0)
			(layers "F.Cu" "F.Mask" "F.Paste")
			(net "GND")
		)
	)
	(footprint ""
		(layer "F.Cu")
		(at 43.754294 -16.099536 90)
		(property "Reference" "C698"
			(at 0 0 90)
			(layer "F.SilkS")
			(hide yes)
			(effects
				(font
					(size 1.27 1.27)
				)
			)
		)
		(property "Value" ""
			(at 0 0 90)
			(layer "F.Fab")
			(effects
				(font
					(size 1.27 1.27)
				)
			)
		)
		(duplicate_pad_numbers_are_jumpers no)
		(fp_line
			(start 0.299974 -0.150114)
			(end 0.299974 0.150114)
			(stroke
				(width 0.1)
				(type default)
			)
			(layer "F.Fab")
		)
		(fp_line
			(start -0.299974 -0.150114)
			(end 0.299974 -0.150114)
			(stroke
				(width 0.1)
				(type default)
			)
			(layer "F.Fab")
		)
		(fp_line
			(start 0.299974 0.150114)
			(end -0.299974 0.150114)
			(stroke
				(width 0.1)
				(type default)
			)
			(layer "F.Fab")
		)
		(fp_line
			(start -0.299974 0.150114)
			(end -0.299974 -0.150114)
			(stroke
				(width 0.1)
				(type default)
			)
			(layer "F.Fab")
		)
		(pad "1" smd rect
			(at -0.2667 0 90)
			(size 0.3048 0.381)
			(layers "F.Cu" "F.Mask" "F.Paste")
			(net "P5E_CPU1_G1_TX_C_DN<5>")
		)
		(pad "2" smd rect
			(at 0.2667 0 90)
			(size 0.3048 0.381)
			(layers "F.Cu" "F.Mask" "F.Paste")
			(net "P5E_CPU1_G1_TX_DN<5>")
		)
	)
	(footprint ""
		(layer "F.Cu")
		(at 211.074 -129.54 -90)
		(property "Reference" "R568"
			(at 0 0 270)
			(layer "F.SilkS")
			(hide yes)
			(effects
				(font
					(size 1.27 1.27)
				)
			)
		)
		(property "Value" ""
			(at 0 0 270)
			(layer "F.Fab")
			(effects
				(font
					(size 1.27 1.27)
				)
			)
		)
		(duplicate_pad_numbers_are_jumpers no)
		(fp_line
			(start -0.7874 0.4064)
			(end -0.7874 -0.4064)
			(stroke
				(width 0.1524)
				(type default)
			)
			(layer "F.SilkS")
		)
		(fp_line
			(start 0.7874 0.4064)
			(end -0.7874 0.4064)
			(stroke
				(width 0.1524)
				(type default)
			)
			(layer "F.SilkS")
		)
		(fp_line
			(start -0.7874 -0.4064)
			(end 0.7874 -0.4064)
			(stroke
				(width 0.1524)
				(type default)
			)
			(layer "F.SilkS")
		)
		(fp_line
			(start 0.7874 -0.4064)
			(end 0.7874 0.4064)
			(stroke
				(width 0.1524)
				(type default)
			)
			(layer "F.SilkS")
		)
		(fp_line
			(start -0.67945 0.3048)
			(end -0.67945 -0.305054)
			(stroke
				(width 0.1)
				(type default)
			)
			(layer "F.Fab")
		)
		(fp_line
			(start -0.12065 0.3048)
			(end -0.67945 0.3048)
			(stroke
				(width 0.1)
				(type default)
			)
			(layer "F.Fab")
		)
		(fp_line
			(start 0.120396 0.3048)
			(end 0.120396 0.2794)
			(stroke
				(width 0.1)
				(type default)
			)
			(layer "F.Fab")
		)
		(fp_line
			(start 0.67945 0.3048)
			(end 0.120396 0.3048)
			(stroke
				(width 0.1)
				(type default)
			)
			(layer "F.Fab")
		)
		(fp_line
			(start -0.12065 0.2794)
			(end -0.12065 0.3048)
			(stroke
				(width 0.1)
				(type default)
			)
			(layer "F.Fab")
		)
		(fp_line
			(start 0.120396 0.2794)
			(end -0.12065 0.2794)
			(stroke
				(width 0.1)
				(type default)
			)
			(layer "F.Fab")
		)
		(fp_line
			(start -0.12065 -0.2794)
			(end 0.12065 -0.2794)
			(stroke
				(width 0.1)
				(type default)
			)
			(layer "F.Fab")
		)
		(fp_line
			(start 0.12065 -0.2794)
			(end 0.12065 -0.3048)
			(stroke
				(width 0.1)
				(type default)
			)
			(layer "F.Fab")
		)
		(fp_line
			(start 0.12065 -0.3048)
			(end 0.67945 -0.3048)
			(stroke
				(width 0.1)
				(type default)
			)
			(layer "F.Fab")
		)
		(fp_line
			(start 0.67945 -0.3048)
			(end 0.67945 0.3048)
			(stroke
				(width 0.1)
				(type default)
			)
			(layer "F.Fab")
		)
		(fp_line
			(start -0.67945 -0.305054)
			(end -0.12065 -0.305054)
			(stroke
				(width 0.1)
				(type default)
			)
			(layer "F.Fab")
		)
		(fp_line
			(start -0.12065 -0.305054)
			(end -0.12065 -0.2794)
			(stroke
				(width 0.1)
				(type default)
			)
			(layer "F.Fab")
		)
		(pad "1" smd circle
			(at -0.40005 0 270)
			(size 0 0)
			(layers "F.Cu" "F.Mask" "F.Paste")
			(net "P12V_AUX")
		)
		(pad "2" smd circle
			(at 0.40005 0 270)
			(size 0 0)
			(layers "F.Cu" "F.Mask" "F.Paste")
			(net "SW_P3V3_EN_ISO_R")
		)
	)
	(footprint ""
		(layer "F.Cu")
		(at 291.509958 -397.59001 180)
		(property "Reference" "R836"
			(at 0 0 180)
			(layer "F.SilkS")
			(hide yes)
			(effects
				(font
					(size 1.27 1.27)
				)
			)
		)
		(property "Value" ""
			(at 0 0 180)
			(layer "F.Fab")
			(effects
				(font
					(size 1.27 1.27)
				)
			)
		)
		(duplicate_pad_numbers_are_jumpers no)
		(fp_line
			(start 0.32512 0.175006)
			(end -0.32512 0.175006)
			(stroke
				(width 0.1)
				(type default)
			)
			(layer "F.Fab")
		)
		(fp_line
			(start 0.32512 -0.175006)
			(end 0.32512 0.175006)
			(stroke
				(width 0.1)
				(type default)
			)
			(layer "F.Fab")
		)
		(fp_line
			(start -0.32512 0.175006)
			(end -0.32512 -0.175006)
			(stroke
				(width 0.1)
				(type default)
			)
			(layer "F.Fab")
		)
		(fp_line
			(start -0.32512 -0.175006)
			(end 0.32512 -0.175006)
			(stroke
				(width 0.1)
				(type default)
			)
			(layer "F.Fab")
		)
		(pad "1" smd rect
			(at -0.2667 0 180)
			(size 0.3048 0.381)
			(layers "F.Cu" "F.Mask" "F.Paste")
			(net "P1V8_CPU0_RT_1D")
		)
		(pad "2" smd rect
			(at 0.2667 0)
			(size 0.3048 0.381)
			(layers "F.Cu" "F.Mask" "F.Paste")
			(net "SMB_RT_CPU0_P1_ROM_R_SDA")
		)
	)
	(footprint ""
		(layer "F.Cu")
		(at 28.537662 -419.249098 90)
		(property "Reference" "R3271"
			(at 0 0 90)
			(layer "F.SilkS")
			(hide yes)
			(effects
				(font
					(size 1.27 1.27)
				)
			)
		)
		(property "Value" ""
			(at 0 0 90)
			(layer "F.Fab")
			(effects
				(font
					(size 1.27 1.27)
				)
			)
		)
		(duplicate_pad_numbers_are_jumpers no)
		(fp_line
			(start 0.7874 -0.4064)
			(end 0.7874 0.4064)
			(stroke
				(width 0.1524)
				(type default)
			)
			(layer "F.SilkS")
		)
		(fp_line
			(start -0.7874 -0.4064)
			(end 0.7874 -0.4064)
			(stroke
				(width 0.1524)
				(type default)
			)
			(layer "F.SilkS")
		)
		(fp_line
			(start 0.7874 0.4064)
			(end -0.7874 0.4064)
			(stroke
				(width 0.1524)
				(type default)
			)
			(layer "F.SilkS")
		)
		(fp_line
			(start -0.7874 0.4064)
			(end -0.7874 -0.4064)
			(stroke
				(width 0.1524)
				(type default)
			)
			(layer "F.SilkS")
		)
		(fp_line
			(start -0.12065 -0.305054)
			(end -0.12065 -0.2794)
			(stroke
				(width 0.1)
				(type default)
			)
			(layer "F.Fab")
		)
		(fp_line
			(start -0.67945 -0.305054)
			(end -0.12065 -0.305054)
			(stroke
				(width 0.1)
				(type default)
			)
			(layer "F.Fab")
		)
		(fp_line
			(start 0.67945 -0.3048)
			(end 0.67945 0.3048)
			(stroke
				(width 0.1)
				(type default)
			)
			(layer "F.Fab")
		)
		(fp_line
			(start 0.12065 -0.3048)
			(end 0.67945 -0.3048)
			(stroke
				(width 0.1)
				(type default)
			)
			(layer "F.Fab")
		)
		(fp_line
			(start 0.12065 -0.2794)
			(end 0.12065 -0.3048)
			(stroke
				(width 0.1)
				(type default)
			)
			(layer "F.Fab")
		)
		(fp_line
			(start -0.12065 -0.2794)
			(end 0.12065 -0.2794)
			(stroke
				(width 0.1)
				(type default)
			)
			(layer "F.Fab")
		)
		(fp_line
			(start 0.120396 0.2794)
			(end -0.12065 0.2794)
			(stroke
				(width 0.1)
				(type default)
			)
			(layer "F.Fab")
		)
		(fp_line
			(start -0.12065 0.2794)
			(end -0.12065 0.3048)
			(stroke
				(width 0.1)
				(type default)
			)
			(layer "F.Fab")
		)
		(fp_line
			(start 0.67945 0.3048)
			(end 0.120396 0.3048)
			(stroke
				(width 0.1)
				(type default)
			)
			(layer "F.Fab")
		)
		(fp_line
			(start 0.120396 0.3048)
			(end 0.120396 0.2794)
			(stroke
				(width 0.1)
				(type default)
			)
			(layer "F.Fab")
		)
		(fp_line
			(start -0.12065 0.3048)
			(end -0.67945 0.3048)
			(stroke
				(width 0.1)
				(type default)
			)
			(layer "F.Fab")
		)
		(fp_line
			(start -0.67945 0.3048)
			(end -0.67945 -0.305054)
			(stroke
				(width 0.1)
				(type default)
			)
			(layer "F.Fab")
		)
		(pad "1" smd circle
			(at -0.40005 0 90)
			(size 0 0)
			(layers "F.Cu" "F.Mask" "F.Paste")
			(net "P3V3_AUX")
		)
		(pad "2" smd circle
			(at 0.40005 0 90)
			(size 0 0)
			(layers "F.Cu" "F.Mask" "F.Paste")
			(net "FM_P2E_EQA1")
		)
	)
	(footprint ""
		(layer "F.Cu")
		(at 434.678836 -168.208452)
		(property "Reference" "R5008"
			(at 0 0 0)
			(layer "F.SilkS")
			(hide yes)
			(effects
				(font
					(size 1.27 1.27)
				)
			)
		)
		(property "Value" ""
			(at 0 0 0)
			(layer "F.Fab")
			(effects
				(font
					(size 1.27 1.27)
				)
			)
		)
		(duplicate_pad_numbers_are_jumpers no)
		(fp_line
			(start -0.7874 -0.4064)
			(end 0.7874 -0.4064)
			(stroke
				(width 0.1524)
				(type default)
			)
			(layer "F.SilkS")
		)
		(fp_line
			(start -0.7874 0.4064)
			(end -0.7874 -0.4064)
			(stroke
				(width 0.1524)
				(type default)
			)
			(layer "F.SilkS")
		)
		(fp_line
			(start 0.7874 -0.4064)
			(end 0.7874 0.4064)
			(stroke
				(width 0.1524)
				(type default)
			)
			(layer "F.SilkS")
		)
		(fp_line
			(start 0.7874 0.4064)
			(end -0.7874 0.4064)
			(stroke
				(width 0.1524)
				(type default)
			)
			(layer "F.SilkS")
		)
		(fp_line
			(start -0.67945 -0.305054)
			(end -0.12065 -0.305054)
			(stroke
				(width 0.1)
				(type default)
			)
			(layer "F.Fab")
		)
		(fp_line
			(start -0.67945 0.3048)
			(end -0.67945 -0.305054)
			(stroke
				(width 0.1)
				(type default)
			)
			(layer "F.Fab")
		)
		(fp_line
			(start -0.12065 -0.305054)
			(end -0.12065 -0.2794)
			(stroke
				(width 0.1)
				(type default)
			)
			(layer "F.Fab")
		)
		(fp_line
			(start -0.12065 -0.2794)
			(end 0.12065 -0.2794)
			(stroke
				(width 0.1)
				(type default)
			)
			(layer "F.Fab")
		)
		(fp_line
			(start -0.12065 0.2794)
			(end -0.12065 0.3048)
			(stroke
				(width 0.1)
				(type default)
			)
			(layer "F.Fab")
		)
		(fp_line
			(start -0.12065 0.3048)
			(end -0.67945 0.3048)
			(stroke
				(width 0.1)
				(type default)
			)
			(layer "F.Fab")
		)
		(fp_line
			(start 0.120396 0.2794)
			(end -0.12065 0.2794)
			(stroke
				(width 0.1)
				(type default)
			)
			(layer "F.Fab")
		)
		(fp_line
			(start 0.120396 0.3048)
			(end 0.120396 0.2794)
			(stroke
				(width 0.1)
				(type default)
			)
			(layer "F.Fab")
		)
		(fp_line
			(start 0.12065 -0.3048)
			(end 0.67945 -0.3048)
			(stroke
				(width 0.1)
				(type default)
			)
			(layer "F.Fab")
		)
		(fp_line
			(start 0.12065 -0.2794)
			(end 0.12065 -0.3048)
			(stroke
				(width 0.1)
				(type default)
			)
			(layer "F.Fab")
		)
		(fp_line
			(start 0.67945 -0.3048)
			(end 0.67945 0.3048)
			(stroke
				(width 0.1)
				(type default)
			)
			(layer "F.Fab")
		)
		(fp_line
			(start 0.67945 0.3048)
			(end 0.120396 0.3048)
			(stroke
				(width 0.1)
				(type default)
			)
			(layer "F.Fab")
		)
		(pad "1" smd circle
			(at -0.40005 0)
			(size 0 0)
			(layers "F.Cu" "F.Mask" "F.Paste")
			(net "PVDD11_S3_P0")
		)
		(pad "2" smd circle
			(at 0.40005 0)
			(size 0 0)
			(layers "F.Cu" "F.Mask" "F.Paste")
			(net "I3C_SPD_DDRGL_CPU0_LVC1_SCL")
		)
	)
	(footprint ""
		(layer "F.Cu")
		(at 148.494242 -104.608884)
		(property "Reference" "R5377"
			(at 0 0 0)
			(layer "F.SilkS")
			(hide yes)
			(effects
				(font
					(size 1.27 1.27)
				)
			)
		)
		(property "Value" ""
			(at 0 0 0)
			(layer "F.Fab")
			(effects
				(font
					(size 1.27 1.27)
				)
			)
		)
		(duplicate_pad_numbers_are_jumpers no)
		(fp_line
			(start -0.7874 -0.4064)
			(end 0.7874 -0.4064)
			(stroke
				(width 0.1524)
				(type default)
			)
			(layer "F.SilkS")
		)
		(fp_line
			(start -0.7874 0.4064)
			(end -0.7874 -0.4064)
			(stroke
				(width 0.1524)
				(type default)
			)
			(layer "F.SilkS")
		)
		(fp_line
			(start 0.7874 -0.4064)
			(end 0.7874 0.4064)
			(stroke
				(width 0.1524)
				(type default)
			)
			(layer "F.SilkS")
		)
		(fp_line
			(start 0.7874 0.4064)
			(end -0.7874 0.4064)
			(stroke
				(width 0.1524)
				(type default)
			)
			(layer "F.SilkS")
		)
		(fp_line
			(start -0.67945 -0.305054)
			(end -0.12065 -0.305054)
			(stroke
				(width 0.1)
				(type default)
			)
			(layer "F.Fab")
		)
		(fp_line
			(start -0.67945 0.3048)
			(end -0.67945 -0.305054)
			(stroke
				(width 0.1)
				(type default)
			)
			(layer "F.Fab")
		)
		(fp_line
			(start -0.12065 -0.305054)
			(end -0.12065 -0.2794)
			(stroke
				(width 0.1)
				(type default)
			)
			(layer "F.Fab")
		)
		(fp_line
			(start -0.12065 -0.2794)
			(end 0.12065 -0.2794)
			(stroke
				(width 0.1)
				(type default)
			)
			(layer "F.Fab")
		)
		(fp_line
			(start -0.12065 0.2794)
			(end -0.12065 0.3048)
			(stroke
				(width 0.1)
				(type default)
			)
			(layer "F.Fab")
		)
		(fp_line
			(start -0.12065 0.3048)
			(end -0.67945 0.3048)
			(stroke
				(width 0.1)
				(type default)
			)
			(layer "F.Fab")
		)
		(fp_line
			(start 0.120396 0.2794)
			(end -0.12065 0.2794)
			(stroke
				(width 0.1)
				(type default)
			)
			(layer "F.Fab")
		)
		(fp_line
			(start 0.120396 0.3048)
			(end 0.120396 0.2794)
			(stroke
				(width 0.1)
				(type default)
			)
			(layer "F.Fab")
		)
		(fp_line
			(start 0.12065 -0.3048)
			(end 0.67945 -0.3048)
			(stroke
				(width 0.1)
				(type default)
			)
			(layer "F.Fab")
		)
		(fp_line
			(start 0.12065 -0.2794)
			(end 0.12065 -0.3048)
			(stroke
				(width 0.1)
				(type default)
			)
			(layer "F.Fab")
		)
		(fp_line
			(start 0.67945 -0.3048)
			(end 0.67945 0.3048)
			(stroke
				(width 0.1)
				(type default)
			)
			(layer "F.Fab")
		)
		(fp_line
			(start 0.67945 0.3048)
			(end 0.120396 0.3048)
			(stroke
				(width 0.1)
				(type default)
			)
			(layer "F.Fab")
		)
		(pad "1" smd circle
			(at -0.40005 0)
			(size 0 0)
			(layers "F.Cu" "F.Mask" "F.Paste")
			(net "HDD_ACTIVITY_BUF_N")
		)
		(pad "2" smd circle
			(at 0.40005 0)
			(size 0 0)
			(layers "F.Cu" "F.Mask" "F.Paste")
			(net "PU_BUFFER_HDD_ACTIVITY")
		)
	)
)
